# T6G (Grand Teton) — schematic netlist excerpt (pin names and nets, part order shuffled) for the footprints in the layout excerpt that follows; sources: Cadence DE-HDL packaged netlist, KiCad conversion of 04192023_DAF0TMB3IC0_F0TG_MB_C_brd_V02_OCP.brd

R155  Q_RES  1K 1% EMPTY  pkg 0402LF  page 144 : A = P3V3_AUX ; B = M2_SSD0_CLKREQ_EN_N_BUF
R50  Q_RES  33 5% CHIP  pkg 0402LF  page 80 : A = SCM_JTAG_MUX_R_S1 ; B = SCM_JTAG_MUX_S1

(kicad_pcb
	(version 20260206)
	(generator "pcbnew")
	(generator_version "10.0")
	(general
		(thickness 1.6)
		(legacy_teardrops no)
	)
	(paper "A4")
	(title_block
		(title "04192023_DAF0TMB3IC0_F0TG_MB_C_brd_V02_OCP.brd")
		(comment 1 "Grand Teton / footprints 3272-3273 of 8354")
	)
	(layers
		(0 "F.Cu" signal "TOP")
		(4 "In1.Cu" signal "GND")
		(6 "In2.Cu" signal "IN1")
		(8 "In3.Cu" signal "GND1")
		(10 "In4.Cu" signal "IN2")
		(12 "In5.Cu" signal "GND2")
		(14 "In6.Cu" signal "IN3")
		(16 "In7.Cu" signal "GND3")
		(18 "In8.Cu" signal "VCC")
		(20 "In9.Cu" signal "VCC1")
		(22 "In10.Cu" signal "GND4")
		(24 "In11.Cu" signal "IN4")
		(26 "In12.Cu" signal "GND5")
		(28 "In13.Cu" signal "IN5")
		(30 "In14.Cu" signal "GND6")
		(32 "In15.Cu" signal "IN6")
		(34 "In16.Cu" signal "GND7")
		(2 "B.Cu" signal "BOTTOM")
		(9 "F.Adhes" user "F.Adhesive")
		(11 "B.Adhes" user "B.Adhesive")
		(13 "F.Paste" user "Package Geometry/Pastemask Top")
		(15 "B.Paste" user "Package Geometry/Pastemask Bottom")
		(5 "F.SilkS" user "Ref Des/Silkscreen Top")
		(7 "B.SilkS" user "Ref Des/Silkscreen Bottom")
		(1 "F.Mask" user "Board Geometry/Soldermask Top")
		(3 "B.Mask" user "Board Geometry/Soldermask Bottom")
		(17 "Dwgs.User" user "User.Drawings")
		(19 "Cmts.User" user "User.Comments")
		(21 "Eco1.User" user "User.Eco1")
		(23 "Eco2.User" user "User.Eco2")
		(25 "Edge.Cuts" user "Board Geometry/Outline")
		(27 "Margin" user)
		(31 "F.CrtYd" user "Package Geometry/Place Bound Top")
		(29 "B.CrtYd" user "Package Geometry/Place Bound Bottom")
		(35 "F.Fab" user "Ref Des/Assembly Top")
		(33 "B.Fab" user "Ref Des/Assembly Bottom")
	)
	(footprint ""
		(layer "F.Cu")
		(at 164.544756 -42.177462)
		(property "Reference" "R155"
			(at 0 0 0)
			(layer "F.SilkS")
			(hide yes)
			(effects
				(font
					(size 1.27 1.27)
				)
			)
		)
		(property "Value" ""
			(at 0 0 0)
			(layer "F.Fab")
			(effects
				(font
					(size 1.27 1.27)
				)
			)
		)
		(duplicate_pad_numbers_are_jumpers no)
		(fp_line
			(start -0.7874 -0.4064)
			(end 0.7874 -0.4064)
			(stroke
				(width 0.1524)
				(type default)
			)
			(layer "F.SilkS")
		)
		(fp_line
			(start -0.7874 0.4064)
			(end -0.7874 -0.4064)
			(stroke
				(width 0.1524)
				(type default)
			)
			(layer "F.SilkS")
		)
		(fp_line
			(start 0.7874 -0.4064)
			(end 0.7874 0.4064)
			(stroke
				(width 0.1524)
				(type default)
			)
			(layer "F.SilkS")
		)
		(fp_line
			(start 0.7874 0.4064)
			(end -0.7874 0.4064)
			(stroke
				(width 0.1524)
				(type default)
			)
			(layer "F.SilkS")
		)
		(fp_line
			(start -0.67945 -0.305054)
			(end -0.12065 -0.305054)
			(stroke
				(width 0.1)
				(type default)
			)
			(layer "F.Fab")
		)
		(fp_line
			(start -0.67945 0.3048)
			(end -0.67945 -0.305054)
			(stroke
				(width 0.1)
				(type default)
			)
			(layer "F.Fab")
		)
		(fp_line
			(start -0.12065 -0.305054)
			(end -0.12065 -0.2794)
			(stroke
				(width 0.1)
				(type default)
			)
			(layer "F.Fab")
		)
		(fp_line
			(start -0.12065 -0.2794)
			(end 0.12065 -0.2794)
			(stroke
				(width 0.1)
				(type default)
			)
			(layer "F.Fab")
		)
		(fp_line
			(start -0.12065 0.2794)
			(end -0.12065 0.3048)
			(stroke
				(width 0.1)
				(type default)
			)
			(layer "F.Fab")
		)
		(fp_line
			(start -0.12065 0.3048)
			(end -0.67945 0.3048)
			(stroke
				(width 0.1)
				(type default)
			)
			(layer "F.Fab")
		)
		(fp_line
			(start 0.120396 0.2794)
			(end -0.12065 0.2794)
			(stroke
				(width 0.1)
				(type default)
			)
			(layer "F.Fab")
		)
		(fp_line
			(start 0.120396 0.3048)
			(end 0.120396 0.2794)
			(stroke
				(width 0.1)
				(type default)
			)
			(layer "F.Fab")
		)
		(fp_line
			(start 0.12065 -0.3048)
			(end 0.67945 -0.3048)
			(stroke
				(width 0.1)
				(type default)
			)
			(layer "F.Fab")
		)
		(fp_line
			(start 0.12065 -0.2794)
			(end 0.12065 -0.3048)
			(stroke
				(width 0.1)
				(type default)
			)
			(layer "F.Fab")
		)
		(fp_line
			(start 0.67945 -0.3048)
			(end 0.67945 0.3048)
			(stroke
				(width 0.1)
				(type default)
			)
			(layer "F.Fab")
		)
		(fp_line
			(start 0.67945 0.3048)
			(end 0.120396 0.3048)
			(stroke
				(width 0.1)
				(type default)
			)
			(layer "F.Fab")
		)
		(pad "1" smd circle
			(at -0.40005 0)
			(size 0 0)
			(layers "F.Cu" "F.Mask" "F.Paste")
			(net "P3V3_AUX")
		)
		(pad "2" smd circle
			(at 0.40005 0)
			(size 0 0)
			(layers "F.Cu" "F.Mask" "F.Paste")
			(net "M2_SSD0_CLKREQ_EN_N_BUF")
		)
	)
	(footprint ""
		(layer "F.Cu")
		(at 171.196 -108.168948 180)
		(property "Reference" "R50"
			(at 0 0 180)
			(layer "F.SilkS")
			(hide yes)
			(effects
				(font
					(size 1.27 1.27)
				)
			)
		)
		(property "Value" ""
			(at 0 0 180)
			(layer "F.Fab")
			(effects
				(font
					(size 1.27 1.27)
				)
			)
		)
		(duplicate_pad_numbers_are_jumpers no)
		(fp_line
			(start 0.7874 0.4064)
			(end -0.7874 0.4064)
			(stroke
				(width 0.1524)
				(type default)
			)
			(layer "F.SilkS")
		)
		(fp_line
			(start 0.7874 -0.4064)
			(end 0.7874 0.4064)
			(stroke
				(width 0.1524)
				(type default)
			)
			(layer "F.SilkS")
		)
		(fp_line
			(start -0.7874 0.4064)
			(end -0.7874 -0.4064)
			(stroke
				(width 0.1524)
				(type default)
			)
			(layer "F.SilkS")
		)
		(fp_line
			(start -0.7874 -0.4064)
			(end 0.7874 -0.4064)
			(stroke
				(width 0.1524)
				(type default)
			)
			(layer "F.SilkS")
		)
		(fp_line
			(start 0.67945 0.3048)
			(end 0.120396 0.3048)
			(stroke
				(width 0.1)
				(type default)
			)
			(layer "F.Fab")
		)
		(fp_line
			(start 0.67945 -0.3048)
			(end 0.67945 0.3048)
			(stroke
				(width 0.1)
				(type default)
			)
			(layer "F.Fab")
		)
		(fp_line
			(start 0.12065 -0.2794)
			(end 0.12065 -0.3048)
			(stroke
				(width 0.1)
				(type default)
			)
			(layer "F.Fab")
		)
		(fp_line
			(start 0.12065 -0.3048)
			(end 0.67945 -0.3048)
			(stroke
				(width 0.1)
				(type default)
			)
			(layer "F.Fab")
		)
		(fp_line
			(start 0.120396 0.3048)
			(end 0.120396 0.2794)
			(stroke
				(width 0.1)
				(type default)
			)
			(layer "F.Fab")
		)
		(fp_line
			(start 0.120396 0.2794)
			(end -0.12065 0.2794)
			(stroke
				(width 0.1)
				(type default)
			)
			(layer "F.Fab")
		)
		(fp_line
			(start -0.12065 0.3048)
			(end -0.67945 0.3048)
			(stroke
				(width 0.1)
				(type default)
			)
			(layer "F.Fab")
		)
		(fp_line
			(start -0.12065 0.2794)
			(end -0.12065 0.3048)
			(stroke
				(width 0.1)
				(type default)
			)
			(layer "F.Fab")
		)
		(fp_line
			(start -0.12065 -0.2794)
			(end 0.12065 -0.2794)
			(stroke
				(width 0.1)
				(type default)
			)
			(layer "F.Fab")
		)
		(fp_line
			(start -0.12065 -0.305054)
			(end -0.12065 -0.2794)
			(stroke
				(width 0.1)
				(type default)
			)
			(layer "F.Fab")
		)
		(fp_line
			(start -0.67945 0.3048)
			(end -0.67945 -0.305054)
			(stroke
				(width 0.1)
				(type default)
			)
			(layer "F.Fab")
		)
		(fp_line
			(start -0.67945 -0.305054)
			(end -0.12065 -0.305054)
			(stroke
				(width 0.1)
				(type default)
			)
			(layer "F.Fab")
		)
		(pad "1" smd circle
			(at -0.40005 0 180)
			(size 0 0)
			(layers "F.Cu" "F.Mask" "F.Paste")
			(net "SCM_JTAG_MUX_R_S1")
		)
		(pad "2" smd circle
			(at 0.40005 0 180)
			(size 0 0)
			(layers "F.Cu" "F.Mask" "F.Paste")
			(net "SCM_JTAG_MUX_S1")
		)
	)
)
